# SCM (Grand Teton) — schematic netlist excerpt (pin names and nets, part order shuffled) for the footprints in the layout excerpt that follows; sources: Cadence DE-HDL packaged netlist, KiCad conversion of 12092022_DA0F0TMDCD0_F0T_Management_Board_D_brd_V3_OCP.brd

X20  TP_TDR_4P_FTS  TP_TDR_4P_DIP EMPTY  pkg TH  page 60
  S1  = TDR_DIFF_100_IN1_DN
  P1  = GND_P1
  P2  = GND_P1
  S2  = TDR_DIFF_100_IN1_DP

R645  Q_RES  0 5% EMPTY  pkg 0603LF  page 17 : A = P1V8_AUX ; B = PGPPA_BMC_AUX_L

(kicad_pcb
	(version 20260206)
	(generator "pcbnew")
	(generator_version "10.0")
	(general
		(thickness 1.6)
		(legacy_teardrops no)
	)
	(paper "A4")
	(title_block
		(title "12092022_DA0F0TMDCD0_F0T_Management_Board_D_brd_V3_OCP.brd")
		(comment 1 "Grand Teton / footprints 942-943 of 1440")
	)
	(layers
		(0 "F.Cu" signal "TOP")
		(4 "In1.Cu" signal "GND")
		(6 "In2.Cu" signal "IN1")
		(8 "In3.Cu" signal "GND1")
		(10 "In4.Cu" signal "IN2")
		(12 "In5.Cu" signal "VCC")
		(14 "In6.Cu" signal "VCC1")
		(16 "In7.Cu" signal "IN3")
		(18 "In8.Cu" signal "GND2")
		(20 "In9.Cu" signal "IN4")
		(22 "In10.Cu" signal "GND3")
		(2 "B.Cu" signal "BOTTOM")
		(9 "F.Adhes" user "F.Adhesive")
		(11 "B.Adhes" user "B.Adhesive")
		(13 "F.Paste" user "Package Geometry/Pastemask Top")
		(15 "B.Paste" user "Package Geometry/Pastemask Bottom")
		(5 "F.SilkS" user "Ref Des/Silkscreen Top")
		(7 "B.SilkS" user "Ref Des/Silkscreen Bottom")
		(1 "F.Mask" user "Board Geometry/Soldermask Top")
		(3 "B.Mask" user "Board Geometry/Soldermask Bottom")
		(17 "Dwgs.User" user "User.Drawings")
		(19 "Cmts.User" user "User.Comments")
		(21 "Eco1.User" user "User.Eco1")
		(23 "Eco2.User" user "User.Eco2")
		(25 "Edge.Cuts" user "Board Geometry/Outline")
		(27 "Margin" user)
		(31 "F.CrtYd" user "Package Geometry/Place Bound Top")
		(29 "B.CrtYd" user "Package Geometry/Place Bound Bottom")
		(35 "F.Fab" user "Ref Des/Assembly Top")
		(33 "B.Fab" user "Ref Des/Assembly Bottom")
	)
	(footprint ""
		(layer "B.Cu")
		(at 68.6308 -93.7514 90)
		(property "Reference" "R645"
			(at 0 0 90)
			(layer "B.SilkS")
			(hide yes)
			(effects
				(font
					(size 1.27 1.27)
				)
				(justify mirror)
			)
		)
		(property "Value" ""
			(at 0 0 90)
			(layer "B.Fab")
			(effects
				(font
					(size 1.27 1.27)
				)
				(justify mirror)
			)
		)
		(duplicate_pad_numbers_are_jumpers no)
		(fp_line
			(start 1.2954 -0.5842)
			(end -1.2954 -0.5842)
			(stroke
				(width 0.1524)
				(type default)
			)
			(layer "B.SilkS")
		)
		(fp_line
			(start -1.2954 -0.5842)
			(end -1.2954 0.5842)
			(stroke
				(width 0.1524)
				(type default)
			)
			(layer "B.SilkS")
		)
		(fp_line
			(start 1.2954 0.5842)
			(end 1.2954 -0.5842)
			(stroke
				(width 0.1524)
				(type default)
			)
			(layer "B.SilkS")
		)
		(fp_line
			(start -1.2954 0.5842)
			(end 1.2954 0.5842)
			(stroke
				(width 0.1524)
				(type default)
			)
			(layer "B.SilkS")
		)
		(fp_line
			(start 0.8636 -0.4572)
			(end -0.8636 -0.4572)
			(stroke
				(width 0.1)
				(type default)
			)
			(layer "B.Fab")
		)
		(fp_line
			(start -0.8636 -0.4572)
			(end -0.8636 -0.406654)
			(stroke
				(width 0.1)
				(type default)
			)
			(layer "B.Fab")
		)
		(fp_line
			(start 1.1938 -0.406654)
			(end 0.8636 -0.406654)
			(stroke
				(width 0.1)
				(type default)
			)
			(layer "B.Fab")
		)
		(fp_line
			(start 0.8636 -0.406654)
			(end 0.8636 -0.4572)
			(stroke
				(width 0.1)
				(type default)
			)
			(layer "B.Fab")
		)
		(fp_line
			(start -0.8636 -0.406654)
			(end -1.1938 -0.406654)
			(stroke
				(width 0.1)
				(type default)
			)
			(layer "B.Fab")
		)
		(fp_line
			(start -1.1938 -0.406654)
			(end -1.1938 0.4064)
			(stroke
				(width 0.1)
				(type default)
			)
			(layer "B.Fab")
		)
		(fp_line
			(start 1.1938 0.4064)
			(end 1.1938 -0.406654)
			(stroke
				(width 0.1)
				(type default)
			)
			(layer "B.Fab")
		)
		(fp_line
			(start 0.8636 0.4064)
			(end 1.1938 0.4064)
			(stroke
				(width 0.1)
				(type default)
			)
			(layer "B.Fab")
		)
		(fp_line
			(start -0.8636 0.4064)
			(end -0.8636 0.4572)
			(stroke
				(width 0.1)
				(type default)
			)
			(layer "B.Fab")
		)
		(fp_line
			(start -1.1938 0.4064)
			(end -0.8636 0.4064)
			(stroke
				(width 0.1)
				(type default)
			)
			(layer "B.Fab")
		)
		(fp_line
			(start 0.8636 0.4318)
			(end 0.8636 0.4064)
			(stroke
				(width 0.1)
				(type default)
			)
			(layer "B.Fab")
		)
		(fp_line
			(start 0.8636 0.4572)
			(end 0.8636 0.4318)
			(stroke
				(width 0.1)
				(type default)
			)
			(layer "B.Fab")
		)
		(fp_line
			(start -0.8636 0.4572)
			(end 0.8636 0.4572)
			(stroke
				(width 0.1)
				(type default)
			)
			(layer "B.Fab")
		)
		(pad "1" smd rect
			(at 0.7366 0)
			(size 0.7112 0.8128)
			(layers "B.Cu" "B.Mask" "B.Paste")
			(net "P1V8_AUX")
		)
		(pad "2" smd rect
			(at -0.7366 0)
			(size 0.7112 0.8128)
			(layers "B.Cu" "B.Mask" "B.Paste")
			(net "PGPPA_BMC_AUX_L")
		)
	)
	(footprint ""
		(layer "B.Cu")
		(at 114.554 34.6964 -90)
		(property "Reference" "X20"
			(at 2.04597 1.2065 0)
			(unlocked yes)
			(layer "B.SilkS")
			(effects
				(font
					(size 0.7874 0.5842)
					(thickness 0.1524)
				)
				(justify left mirror)
			)
		)
		(property "Value" ""
			(at 0 0 90)
			(layer "B.Fab")
			(effects
				(font
					(size 1.27 1.27)
				)
				(justify mirror)
			)
		)
		(property "Device Type" "TP_TDR_4P_FTS_TH-TP_TDR_4P_DIPA"
			(at -1.30175 1.27 180)
			(unlocked yes)
			(layer "B.Fab")
			(hide yes)
			(effects
				(font
					(size 0.635 0.4064)
					(thickness 0.1524)
				)
				(justify mirror)
			)
		)
		(property "User Part Number" "N_A"
			(at -1.30175 1.27 180)
			(unlocked yes)
			(layer "Cmts.User")
			(hide yes)
			(effects
				(font
					(size 0.635 0.4064)
					(thickness 0.1524)
				)
				(justify mirror)
			)
		)
		(duplicate_pad_numbers_are_jumpers no)
		(fp_line
			(start -2.54 3.81)
			(end -2.54 3.6703)
			(stroke
				(width 0.1524)
				(type default)
			)
			(layer "B.SilkS")
		)
		(fp_line
			(start 0 3.81)
			(end -2.54 3.81)
			(stroke
				(width 0.1524)
				(type default)
			)
			(layer "B.SilkS")
		)
		(fp_line
			(start 0 3.175)
			(end 0 3.81)
			(stroke
				(width 0.1524)
				(type default)
			)
			(layer "B.SilkS")
		)
		(fp_line
			(start -2.54 1.4097)
			(end -2.54 1.1303)
			(stroke
				(width 0.1524)
				(type default)
			)
			(layer "B.SilkS")
		)
		(fp_line
			(start 0 0.635)
			(end 0 1.905)
			(stroke
				(width 0.1524)
				(type default)
			)
			(layer "B.SilkS")
		)
		(fp_line
			(start -2.54 -1.1303)
			(end -2.54 -1.27)
			(stroke
				(width 0.1524)
				(type default)
			)
			(layer "B.SilkS")
		)
		(fp_line
			(start -2.54 -1.27)
			(end 0 -1.27)
			(stroke
				(width 0.1524)
				(type default)
			)
			(layer "B.SilkS")
		)
		(fp_line
			(start 0 -1.27)
			(end 0 -0.635)
			(stroke
				(width 0.1524)
				(type default)
			)
			(layer "B.SilkS")
		)
		(fp_poly
			(pts
				(xy 0.761746 0) (xy 2.285746 -0.762) (xy 2.285746 0.762)
			)
			(stroke
				(width 0)
				(type default)
			)
			(fill yes)
			(layer "B.SilkS")
		)
		(fp_line
			(start -2.54 3.81)
			(end -2.54 -1.27)
			(stroke
				(width 0.1)
				(type default)
			)
			(layer "B.Fab")
		)
		(fp_line
			(start 0 3.81)
			(end -2.54 3.81)
			(stroke
				(width 0.1)
				(type default)
			)
			(layer "B.Fab")
		)
		(fp_line
			(start -2.54 -1.27)
			(end 0 -1.27)
			(stroke
				(width 0.1)
				(type default)
			)
			(layer "B.Fab")
		)
		(fp_line
			(start 0 -1.27)
			(end 0 3.81)
			(stroke
				(width 0.1)
				(type default)
			)
			(layer "B.Fab")
		)
		(fp_poly
			(pts
				(xy 0.761746 0) (xy 2.285746 -0.762) (xy 2.285746 0.762)
			)
			(stroke
				(width 0)
				(type default)
			)
			(fill yes)
			(layer "B.Fab")
		)
		(pad "1" thru_hole circle
			(at 0 0 90)
			(size 1.0033 1.0033)
			(drill 0.249936)
			(layers "*.Cu" "*.Mask")
			(remove_unused_layers no)
			(net "TDR_DIFF_100_IN1_DN")
			(clearance 0.10795)
			(padstack
				(mode front_inner_back)
				(layer "Inner"
					(shape circle)
					(size 0.8001 0.8001)
					(clearance 0.1524)
				)
				(layer "B.Cu"
					(shape circle)
					(size 1.0033 1.0033)
					(thermal_gap 0.10795)
					(clearance 0.10795)
				)
			)
		)
		(pad "2" thru_hole circle
			(at -2.54 0 90)
			(size 1.9939 1.9939)
			(drill 0.249936)
			(layers "*.Cu" "*.Mask")
			(remove_unused_layers no)
			(net "GND_P1")
			(clearance 0.10795)
			(padstack
				(mode front_inner_back)
				(layer "Inner"
					(shape circle)
					(size 0.8001 0.8001)
					(clearance 0.1524)
				)
				(layer "B.Cu"
					(shape circle)
					(size 1.9939 1.9939)
					(thermal_gap 0.10795)
					(clearance 0.10795)
				)
			)
		)
		(pad "3" thru_hole circle
			(at -2.54 2.54 90)
			(size 1.9939 1.9939)
			(drill 0.249936)
			(layers "*.Cu" "*.Mask")
			(remove_unused_layers no)
			(net "GND_P1")
			(clearance 0.10795)
			(padstack
				(mode front_inner_back)
				(layer "Inner"
					(shape circle)
					(size 0.8001 0.8001)
					(clearance 0.1524)
				)
				(layer "B.Cu"
					(shape circle)
					(size 1.9939 1.9939)
					(thermal_gap 0.10795)
					(clearance 0.10795)
				)
			)
		)
		(pad "4" thru_hole circle
			(at 0 2.54 90)
			(size 1.0033 1.0033)
			(drill 0.249936)
			(layers "*.Cu" "*.Mask")
			(remove_unused_layers no)
			(net "TDR_DIFF_100_IN1_DP")
			(clearance 0.10795)
			(padstack
				(mode front_inner_back)
				(layer "Inner"
					(shape circle)
					(size 0.8001 0.8001)
					(clearance 0.1524)
				)
				(layer "B.Cu"
					(shape circle)
					(size 1.0033 1.0033)
					(thermal_gap 0.10795)
					(clearance 0.10795)
				)
			)
		)
	)
)
